# T6G (Grand Teton) — schematic netlist excerpt (pin names and nets, part order shuffled) for the footprints in the layout excerpt that follows; sources: Cadence DE-HDL packaged netlist, KiCad conversion of 04192023_DAF0TMB3IC0_F0TG_MB_C_brd_V02_OCP.brd

C1875  Q_CAP  0.1UF 25V 10% X7R  pkg 0402  page 143 : A = P3V3_AUX ; B = GND
C745  Q_CAP_DIFFBUS  DIFF BUS_0.22UF 6.3V 20% X6S  pkg C0201  page 66 : \1\ = P5E_CPU1_P2_TX_C_DP<14> ; \2\ = P5E_CPU1_P2_TX_DP<14>
PC6609_09P1_1  Q_CAP  2.2UF 10V 10% X6S  pkg C0402  page 365 : A = P0V9_RETIMER_CPU1_PVCC ; B = GND

(kicad_pcb
	(version 20260206)
	(generator "pcbnew")
	(generator_version "10.0")
	(general
		(thickness 1.6)
		(legacy_teardrops no)
	)
	(paper "A4")
	(title_block
		(title "04192023_DAF0TMB3IC0_F0TG_MB_C_brd_V02_OCP.brd")
		(comment 1 "Grand Teton / footprints 1925-1927 of 8354")
	)
	(layers
		(0 "F.Cu" signal "TOP")
		(4 "In1.Cu" signal "GND")
		(6 "In2.Cu" signal "IN1")
		(8 "In3.Cu" signal "GND1")
		(10 "In4.Cu" signal "IN2")
		(12 "In5.Cu" signal "GND2")
		(14 "In6.Cu" signal "IN3")
		(16 "In7.Cu" signal "GND3")
		(18 "In8.Cu" signal "VCC")
		(20 "In9.Cu" signal "VCC1")
		(22 "In10.Cu" signal "GND4")
		(24 "In11.Cu" signal "IN4")
		(26 "In12.Cu" signal "GND5")
		(28 "In13.Cu" signal "IN5")
		(30 "In14.Cu" signal "GND6")
		(32 "In15.Cu" signal "IN6")
		(34 "In16.Cu" signal "GND7")
		(2 "B.Cu" signal "BOTTOM")
		(9 "F.Adhes" user "F.Adhesive")
		(11 "B.Adhes" user "B.Adhesive")
		(13 "F.Paste" user "Package Geometry/Pastemask Top")
		(15 "B.Paste" user "Package Geometry/Pastemask Bottom")
		(5 "F.SilkS" user "Ref Des/Silkscreen Top")
		(7 "B.SilkS" user "Ref Des/Silkscreen Bottom")
		(1 "F.Mask" user "Board Geometry/Soldermask Top")
		(3 "B.Mask" user "Board Geometry/Soldermask Bottom")
		(17 "Dwgs.User" user "User.Drawings")
		(19 "Cmts.User" user "User.Comments")
		(21 "Eco1.User" user "User.Eco1")
		(23 "Eco2.User" user "User.Eco2")
		(25 "Edge.Cuts" user "Board Geometry/Outline")
		(27 "Margin" user)
		(31 "F.CrtYd" user "Package Geometry/Place Bound Top")
		(29 "B.CrtYd" user "Package Geometry/Place Bound Bottom")
		(35 "F.Fab" user "Ref Des/Assembly Top")
		(33 "B.Fab" user "Ref Des/Assembly Bottom")
	)
	(footprint ""
		(layer "F.Cu")
		(at 12.860274 -389.044434 -90)
		(property "Reference" "PC6609_09P1_1"
			(at 0 0 270)
			(layer "F.SilkS")
			(hide yes)
			(effects
				(font
					(size 1.27 1.27)
				)
			)
		)
		(property "Value" ""
			(at 0 0 270)
			(layer "F.Fab")
			(effects
				(font
					(size 1.27 1.27)
				)
			)
		)
		(duplicate_pad_numbers_are_jumpers no)
		(fp_line
			(start -0.7874 0.4064)
			(end -0.7874 -0.4064)
			(stroke
				(width 0.1524)
				(type default)
			)
			(layer "F.SilkS")
		)
		(fp_line
			(start 0.7874 0.4064)
			(end -0.7874 0.4064)
			(stroke
				(width 0.1524)
				(type default)
			)
			(layer "F.SilkS")
		)
		(fp_line
			(start -0.7874 -0.4064)
			(end 0.7874 -0.4064)
			(stroke
				(width 0.1524)
				(type default)
			)
			(layer "F.SilkS")
		)
		(fp_line
			(start 0.7874 -0.4064)
			(end 0.7874 0.4064)
			(stroke
				(width 0.1524)
				(type default)
			)
			(layer "F.SilkS")
		)
		(fp_line
			(start -0.67945 0.3048)
			(end -0.67945 -0.305054)
			(stroke
				(width 0.1)
				(type default)
			)
			(layer "F.Fab")
		)
		(fp_line
			(start -0.12065 0.3048)
			(end -0.67945 0.3048)
			(stroke
				(width 0.1)
				(type default)
			)
			(layer "F.Fab")
		)
		(fp_line
			(start 0.120396 0.3048)
			(end 0.120396 0.2794)
			(stroke
				(width 0.1)
				(type default)
			)
			(layer "F.Fab")
		)
		(fp_line
			(start 0.67945 0.3048)
			(end 0.120396 0.3048)
			(stroke
				(width 0.1)
				(type default)
			)
			(layer "F.Fab")
		)
		(fp_line
			(start -0.12065 0.2794)
			(end -0.12065 0.3048)
			(stroke
				(width 0.1)
				(type default)
			)
			(layer "F.Fab")
		)
		(fp_line
			(start 0.120396 0.2794)
			(end -0.12065 0.2794)
			(stroke
				(width 0.1)
				(type default)
			)
			(layer "F.Fab")
		)
		(fp_line
			(start -0.12065 -0.2794)
			(end 0.12065 -0.2794)
			(stroke
				(width 0.1)
				(type default)
			)
			(layer "F.Fab")
		)
		(fp_line
			(start 0.12065 -0.2794)
			(end 0.12065 -0.3048)
			(stroke
				(width 0.1)
				(type default)
			)
			(layer "F.Fab")
		)
		(fp_line
			(start 0.12065 -0.3048)
			(end 0.67945 -0.3048)
			(stroke
				(width 0.1)
				(type default)
			)
			(layer "F.Fab")
		)
		(fp_line
			(start 0.67945 -0.3048)
			(end 0.67945 0.3048)
			(stroke
				(width 0.1)
				(type default)
			)
			(layer "F.Fab")
		)
		(fp_line
			(start -0.67945 -0.305054)
			(end -0.12065 -0.305054)
			(stroke
				(width 0.1)
				(type default)
			)
			(layer "F.Fab")
		)
		(fp_line
			(start -0.12065 -0.305054)
			(end -0.12065 -0.2794)
			(stroke
				(width 0.1)
				(type default)
			)
			(layer "F.Fab")
		)
		(pad "1" smd circle
			(at -0.40005 0 270)
			(size 0 0)
			(layers "F.Cu" "F.Mask" "F.Paste")
			(net "P0V9_RETIMER_CPU1_PVCC")
		)
		(pad "2" smd circle
			(at 0.40005 0 270)
			(size 0 0)
			(layers "F.Cu" "F.Mask" "F.Paste")
			(net "GND")
		)
	)
	(footprint ""
		(layer "F.Cu")
		(at 169.368724 -376.067828)
		(property "Reference" "C745"
			(at 0 0 0)
			(layer "F.SilkS")
			(hide yes)
			(effects
				(font
					(size 1.27 1.27)
				)
			)
		)
		(property "Value" ""
			(at 0 0 0)
			(layer "F.Fab")
			(effects
				(font
					(size 1.27 1.27)
				)
			)
		)
		(duplicate_pad_numbers_are_jumpers no)
		(fp_line
			(start -0.299974 -0.150114)
			(end 0.299974 -0.150114)
			(stroke
				(width 0.1)
				(type default)
			)
			(layer "F.Fab")
		)
		(fp_line
			(start -0.299974 0.150114)
			(end -0.299974 -0.150114)
			(stroke
				(width 0.1)
				(type default)
			)
			(layer "F.Fab")
		)
		(fp_line
			(start 0.299974 -0.150114)
			(end 0.299974 0.150114)
			(stroke
				(width 0.1)
				(type default)
			)
			(layer "F.Fab")
		)
		(fp_line
			(start 0.299974 0.150114)
			(end -0.299974 0.150114)
			(stroke
				(width 0.1)
				(type default)
			)
			(layer "F.Fab")
		)
		(pad "1" smd rect
			(at -0.2667 0)
			(size 0.3048 0.381)
			(layers "F.Cu" "F.Mask" "F.Paste")
			(net "P5E_CPU1_P2_TX_C_DP<14>")
		)
		(pad "2" smd rect
			(at 0.2667 0)
			(size 0.3048 0.381)
			(layers "F.Cu" "F.Mask" "F.Paste")
			(net "P5E_CPU1_P2_TX_DP<14>")
		)
	)
	(footprint ""
		(layer "F.Cu")
		(at 8.42772 -76.144628 90)
		(property "Reference" "C1875"
			(at 0 0 90)
			(layer "F.SilkS")
			(hide yes)
			(effects
				(font
					(size 1.27 1.27)
				)
			)
		)
		(property "Value" ""
			(at 0 0 90)
			(layer "F.Fab")
			(effects
				(font
					(size 1.27 1.27)
				)
			)
		)
		(duplicate_pad_numbers_are_jumpers no)
		(fp_line
			(start 0.7874 -0.4064)
			(end 0.7874 0.4064)
			(stroke
				(width 0.1524)
				(type default)
			)
			(layer "F.SilkS")
		)
		(fp_line
			(start -0.7874 -0.4064)
			(end 0.7874 -0.4064)
			(stroke
				(width 0.1524)
				(type default)
			)
			(layer "F.SilkS")
		)
		(fp_line
			(start 0.7874 0.4064)
			(end -0.7874 0.4064)
			(stroke
				(width 0.1524)
				(type default)
			)
			(layer "F.SilkS")
		)
		(fp_line
			(start -0.7874 0.4064)
			(end -0.7874 -0.4064)
			(stroke
				(width 0.1524)
				(type default)
			)
			(layer "F.SilkS")
		)
		(fp_line
			(start -0.12065 -0.305054)
			(end -0.12065 -0.2794)
			(stroke
				(width 0.1)
				(type default)
			)
			(layer "F.Fab")
		)
		(fp_line
			(start -0.67945 -0.305054)
			(end -0.12065 -0.305054)
			(stroke
				(width 0.1)
				(type default)
			)
			(layer "F.Fab")
		)
		(fp_line
			(start 0.67945 -0.3048)
			(end 0.67945 0.3048)
			(stroke
				(width 0.1)
				(type default)
			)
			(layer "F.Fab")
		)
		(fp_line
			(start 0.12065 -0.3048)
			(end 0.67945 -0.3048)
			(stroke
				(width 0.1)
				(type default)
			)
			(layer "F.Fab")
		)
		(fp_line
			(start 0.12065 -0.2794)
			(end 0.12065 -0.3048)
			(stroke
				(width 0.1)
				(type default)
			)
			(layer "F.Fab")
		)
		(fp_line
			(start -0.12065 -0.2794)
			(end 0.12065 -0.2794)
			(stroke
				(width 0.1)
				(type default)
			)
			(layer "F.Fab")
		)
		(fp_line
			(start 0.120396 0.2794)
			(end -0.12065 0.2794)
			(stroke
				(width 0.1)
				(type default)
			)
			(layer "F.Fab")
		)
		(fp_line
			(start -0.12065 0.2794)
			(end -0.12065 0.3048)
			(stroke
				(width 0.1)
				(type default)
			)
			(layer "F.Fab")
		)
		(fp_line
			(start 0.67945 0.3048)
			(end 0.120396 0.3048)
			(stroke
				(width 0.1)
				(type default)
			)
			(layer "F.Fab")
		)
		(fp_line
			(start 0.120396 0.3048)
			(end 0.120396 0.2794)
			(stroke
				(width 0.1)
				(type default)
			)
			(layer "F.Fab")
		)
		(fp_line
			(start -0.12065 0.3048)
			(end -0.67945 0.3048)
			(stroke
				(width 0.1)
				(type default)
			)
			(layer "F.Fab")
		)
		(fp_line
			(start -0.67945 0.3048)
			(end -0.67945 -0.305054)
			(stroke
				(width 0.1)
				(type default)
			)
			(layer "F.Fab")
		)
		(pad "1" smd circle
			(at -0.40005 0 90)
			(size 0 0)
			(layers "F.Cu" "F.Mask" "F.Paste")
			(net "P3V3_AUX")
		)
		(pad "2" smd circle
			(at 0.40005 0 90)
			(size 0 0)
			(layers "F.Cu" "F.Mask" "F.Paste")
			(net "GND")
		)
	)
)
